(kicad_pcb
	(version 20260206)
	(generator "pcbnew")
	(generator_version "10.0")
	(general
		(thickness 1.6)
		(legacy_teardrops no)
	)
	(paper "A4")
	(title_block
		(title "04192023_DAF0TMB3IC0_F0TG_MB_C_brd_V02_OCP.brd")
		(comment 1 "Grand Teton / footprints 4952-4956 of 8354")
	)
	(layers
		(0 "F.Cu" signal "TOP")
		(4 "In1.Cu" signal "GND")
		(6 "In2.Cu" signal "IN1")
		(8 "In3.Cu" signal "GND1")
		(10 "In4.Cu" signal "IN2")
		(12 "In5.Cu" signal "GND2")
		(14 "In6.Cu" signal "IN3")
		(16 "In7.Cu" signal "GND3")
		(18 "In8.Cu" signal "VCC")
		(20 "In9.Cu" signal "VCC1")
		(22 "In10.Cu" signal "GND4")
		(24 "In11.Cu" signal "IN4")
		(26 "In12.Cu" signal "GND5")
		(28 "In13.Cu" signal "IN5")
		(30 "In14.Cu" signal "GND6")
		(32 "In15.Cu" signal "IN6")
		(34 "In16.Cu" signal "GND7")
		(2 "B.Cu" signal "BOTTOM")
		(9 "F.Adhes" user "F.Adhesive")
		(11 "B.Adhes" user "B.Adhesive")
		(13 "F.Paste" user "Package Geometry/Pastemask Top")
		(15 "B.Paste" user "Package Geometry/Pastemask Bottom")
		(5 "F.SilkS" user "Ref Des/Silkscreen Top")
		(7 "B.SilkS" user "Ref Des/Silkscreen Bottom")
		(1 "F.Mask" user "Board Geometry/Soldermask Top")
		(3 "B.Mask" user "Board Geometry/Soldermask Bottom")
		(17 "Dwgs.User" user "User.Drawings")
		(19 "Cmts.User" user "User.Comments")
		(21 "Eco1.User" user "User.Eco1")
		(23 "Eco2.User" user "User.Eco2")
		(25 "Edge.Cuts" user "Board Geometry/Outline")
		(27 "Margin" user)
		(31 "F.CrtYd" user "Package Geometry/Place Bound Top")
		(29 "B.CrtYd" user "Package Geometry/Place Bound Bottom")
		(35 "F.Fab" user "Ref Des/Assembly Top")
		(33 "B.Fab" user "Ref Des/Assembly Bottom")
	)
	(footprint ""
		(layer "B.Cu")
		(at 176.432972 -414.435544 180)
		(property "Reference" "U195"
			(at -2.873502 -2.892298 0)
			(unlocked yes)
			(layer "B.SilkS")
			(effects
				(font
					(size 0.7874 0.5842)
					(thickness 0.1524)
				)
				(justify left mirror)
			)
		)
		(property "Value" ""
			(at 0 0 0)
			(layer "B.Fab")
			(effects
				(font
					(size 1.27 1.27)
				)
				(justify mirror)
			)
		)
		(duplicate_pad_numbers_are_jumpers no)
		(fp_line
			(start 1.3462 1.100074)
			(end 1.3462 -1.100074)
			(stroke
				(width 0.1524)
				(type default)
			)
			(layer "B.SilkS")
		)
		(fp_line
			(start 1.3462 -1.100074)
			(end 0.670052 -1.100074)
			(stroke
				(width 0.1524)
				(type default)
			)
			(layer "B.SilkS")
		)
		(fp_line
			(start 0.670052 -1.100074)
			(end 0 -0.381)
			(stroke
				(width 0.1524)
				(type default)
			)
			(layer "B.SilkS")
		)
		(fp_line
			(start 0 -0.381)
			(end -0.670052 -1.100074)
			(stroke
				(width 0.1524)
				(type default)
			)
			(layer "B.SilkS")
		)
		(fp_line
			(start -0.670052 -1.100074)
			(end -1.3462 -1.100074)
			(stroke
				(width 0.1524)
				(type default)
			)
			(layer "B.SilkS")
		)
		(fp_line
			(start -1.3462 1.100074)
			(end 1.3462 1.100074)
			(stroke
				(width 0.1524)
				(type default)
			)
			(layer "B.SilkS")
		)
		(fp_line
			(start -1.3462 -1.100074)
			(end -1.3462 1.100074)
			(stroke
				(width 0.1524)
				(type default)
			)
			(layer "B.SilkS")
		)
		(fp_poly
			(pts
				(xy 3.007868 -0.33909) (xy 2.990088 -1.100836) (xy 2.237232 -0.702056)
			)
			(stroke
				(width 0)
				(type default)
			)
			(fill yes)
			(layer "B.SilkS")
		)
		(fp_line
			(start 1.100074 0.8001)
			(end 1.100074 -0.8001)
			(stroke
				(width 0.1)
				(type default)
			)
			(layer "B.Fab")
		)
		(fp_line
			(start 1.100074 -0.8001)
			(end 0.670052 -0.8001)
			(stroke
				(width 0.1)
				(type default)
			)
			(layer "B.Fab")
		)
		(fp_line
			(start 0.670052 1.100074)
			(end 0.670052 0.8001)
			(stroke
				(width 0.1)
				(type default)
			)
			(layer "B.Fab")
		)
		(fp_line
			(start 0.670052 0.8001)
			(end 1.100074 0.8001)
			(stroke
				(width 0.1)
				(type default)
			)
			(layer "B.Fab")
		)
		(fp_line
			(start 0.670052 0.8001)
			(end 0.670052 -0.8001)
			(stroke
				(width 0.1)
				(type default)
			)
			(layer "B.Fab")
		)
		(fp_line
			(start 0.670052 -0.8001)
			(end 0.670052 -1.100074)
			(stroke
				(width 0.1)
				(type default)
			)
			(layer "B.Fab")
		)
		(fp_line
			(start 0.670052 -1.100074)
			(end -0.670052 -1.100074)
			(stroke
				(width 0.1)
				(type default)
			)
			(layer "B.Fab")
		)
		(fp_line
			(start -0.670052 1.100074)
			(end 0.670052 1.100074)
			(stroke
				(width 0.1)
				(type default)
			)
			(layer "B.Fab")
		)
		(fp_line
			(start -0.670052 0.8001)
			(end -0.670052 1.100074)
			(stroke
				(width 0.1)
				(type default)
			)
			(layer "B.Fab")
		)
		(fp_line
			(start -0.670052 -0.8001)
			(end -0.670052 0.8001)
			(stroke
				(width 0.1)
				(type default)
			)
			(layer "B.Fab")
		)
		(fp_line
			(start -0.670052 -0.8001)
			(end -1.100074 -0.8001)
			(stroke
				(width 0.1)
				(type default)
			)
			(layer "B.Fab")
		)
		(fp_line
			(start -0.670052 -1.100074)
			(end -0.670052 -0.8001)
			(stroke
				(width 0.1)
				(type default)
			)
			(layer "B.Fab")
		)
		(fp_line
			(start -1.100074 0.8001)
			(end -0.670052 0.8001)
			(stroke
				(width 0.1)
				(type default)
			)
			(layer "B.Fab")
		)
		(fp_line
			(start -1.100074 -0.8001)
			(end -1.100074 0.8001)
			(stroke
				(width 0.1)
				(type default)
			)
			(layer "B.Fab")
		)
		(fp_poly
			(pts
				(xy 1.524 -0.649986) (xy 2.286 -1.030986) (xy 2.286 -0.268986)
			)
			(stroke
				(width 0)
				(type default)
			)
			(fill yes)
			(layer "B.Fab")
		)
		(pad "1" smd rect
			(at 0.94996 -0.649986 90)
			(size 0.4064 0.508)
			(layers "B.Cu" "B.Mask" "B.Paste")
			(net "BMC_MONITER_R")
		)
		(pad "2" smd rect
			(at 0.94996 0 90)
			(size 0.4064 0.508)
			(layers "B.Cu" "B.Mask" "B.Paste")
			(net "GND")
		)
		(pad "3" smd rect
			(at 0.94996 0.649986 90)
			(size 0.4064 0.508)
			(layers "B.Cu" "B.Mask" "B.Paste")
			(net "RST_SWB_BIC_R_N")
		)
		(pad "4" smd rect
			(at -0.94996 0.649986 90)
			(size 0.4064 0.508)
			(layers "B.Cu" "B.Mask" "B.Paste")
			(net "RST_SWB_BIC_BUF_R_N")
		)
		(pad "5" smd rect
			(at -0.94996 0 90)
			(size 0.4064 0.508)
			(layers "B.Cu" "B.Mask" "B.Paste")
			(net "P3V3_AUX")
		)
		(pad "6" smd rect
			(at -0.94996 -0.649986 90)
			(size 0.4064 0.508)
			(layers "B.Cu" "B.Mask" "B.Paste")
			(net "BMC_MONITER_BUF_R")
		)
	)
	(footprint ""
		(layer "B.Cu")
		(at 449.494402 -424.93311 180)
		(property "Reference" "PR6607"
			(at 0 0 0)
			(layer "B.SilkS")
			(hide yes)
			(effects
				(font
					(size 1.27 1.27)
				)
				(justify mirror)
			)
		)
		(property "Value" ""
			(at 0 0 0)
			(layer "B.Fab")
			(effects
				(font
					(size 1.27 1.27)
				)
				(justify mirror)
			)
		)
		(duplicate_pad_numbers_are_jumpers no)
		(fp_line
			(start 0.7874 0.4064)
			(end 0.7874 -0.4064)
			(stroke
				(width 0.1524)
				(type default)
			)
			(layer "B.SilkS")
		)
		(fp_line
			(start 0.7874 -0.4064)
			(end -0.7874 -0.4064)
			(stroke
				(width 0.1524)
				(type default)
			)
			(layer "B.SilkS")
		)
		(fp_line
			(start -0.7874 0.4064)
			(end 0.7874 0.4064)
			(stroke
				(width 0.1524)
				(type default)
			)
			(layer "B.SilkS")
		)
		(fp_line
			(start -0.7874 -0.4064)
			(end -0.7874 0.4064)
			(stroke
				(width 0.1524)
				(type default)
			)
			(layer "B.SilkS")
		)
		(fp_line
			(start 0.67945 0.3048)
			(end 0.67945 -0.305054)
			(stroke
				(width 0.1)
				(type default)
			)
			(layer "B.Fab")
		)
		(fp_line
			(start 0.67945 -0.305054)
			(end 0.12065 -0.305054)
			(stroke
				(width 0.1)
				(type default)
			)
			(layer "B.Fab")
		)
		(fp_line
			(start 0.12065 0.3048)
			(end 0.67945 0.3048)
			(stroke
				(width 0.1)
				(type default)
			)
			(layer "B.Fab")
		)
		(fp_line
			(start 0.12065 0.2794)
			(end 0.12065 0.3048)
			(stroke
				(width 0.1)
				(type default)
			)
			(layer "B.Fab")
		)
		(fp_line
			(start 0.12065 -0.2794)
			(end -0.12065 -0.2794)
			(stroke
				(width 0.1)
				(type default)
			)
			(layer "B.Fab")
		)
		(fp_line
			(start 0.12065 -0.305054)
			(end 0.12065 -0.2794)
			(stroke
				(width 0.1)
				(type default)
			)
			(layer "B.Fab")
		)
		(fp_line
			(start -0.120396 0.3048)
			(end -0.120396 0.2794)
			(stroke
				(width 0.1)
				(type default)
			)
			(layer "B.Fab")
		)
		(fp_line
			(start -0.120396 0.2794)
			(end 0.12065 0.2794)
			(stroke
				(width 0.1)
				(type default)
			)
			(layer "B.Fab")
		)
		(fp_line
			(start -0.12065 -0.2794)
			(end -0.12065 -0.3048)
			(stroke
				(width 0.1)
				(type default)
			)
			(layer "B.Fab")
		)
		(fp_line
			(start -0.12065 -0.3048)
			(end -0.67945 -0.3048)
			(stroke
				(width 0.1)
				(type default)
			)
			(layer "B.Fab")
		)
		(fp_line
			(start -0.67945 0.3048)
			(end -0.120396 0.3048)
			(stroke
				(width 0.1)
				(type default)
			)
			(layer "B.Fab")
		)
		(fp_line
			(start -0.67945 -0.3048)
			(end -0.67945 0.3048)
			(stroke
				(width 0.1)
				(type default)
			)
			(layer "B.Fab")
		)
		(pad "1" smd circle
			(at 0.40005 0)
			(size 0 0)
			(layers "B.Cu" "B.Mask" "B.Paste")
			(net "P0V9_RETIMER_CPU0_VINSEN")
		)
		(pad "2" smd circle
			(at -0.40005 0)
			(size 0 0)
			(layers "B.Cu" "B.Mask" "B.Paste")
			(net "GND")
		)
	)
	(footprint ""
		(layer "B.Cu")
		(at 84.71916 -390.560052 90)
		(property "Reference" "C318"
			(at 0 0 90)
			(layer "B.SilkS")
			(hide yes)
			(effects
				(font
					(size 1.27 1.27)
				)
				(justify mirror)
			)
		)
		(property "Value" ""
			(at 0 0 90)
			(layer "B.Fab")
			(effects
				(font
					(size 1.27 1.27)
				)
				(justify mirror)
			)
		)
		(duplicate_pad_numbers_are_jumpers no)
		(fp_line
			(start 0.7874 -0.4064)
			(end -0.7874 -0.4064)
			(stroke
				(width 0.1524)
				(type default)
			)
			(layer "B.SilkS")
		)
		(fp_line
			(start -0.7874 -0.4064)
			(end -0.7874 0.4064)
			(stroke
				(width 0.1524)
				(type default)
			)
			(layer "B.SilkS")
		)
		(fp_line
			(start 0.7874 0.4064)
			(end 0.7874 -0.4064)
			(stroke
				(width 0.1524)
				(type default)
			)
			(layer "B.SilkS")
		)
		(fp_line
			(start -0.7874 0.4064)
			(end 0.7874 0.4064)
			(stroke
				(width 0.1524)
				(type default)
			)
			(layer "B.SilkS")
		)
		(fp_line
			(start 0.67945 -0.305054)
			(end 0.12065 -0.305054)
			(stroke
				(width 0.1)
				(type default)
			)
			(layer "B.Fab")
		)
		(fp_line
			(start 0.12065 -0.305054)
			(end 0.12065 -0.2794)
			(stroke
				(width 0.1)
				(type default)
			)
			(layer "B.Fab")
		)
		(fp_line
			(start -0.12065 -0.3048)
			(end -0.67945 -0.3048)
			(stroke
				(width 0.1)
				(type default)
			)
			(layer "B.Fab")
		)
		(fp_line
			(start -0.67945 -0.3048)
			(end -0.67945 0.3048)
			(stroke
				(width 0.1)
				(type default)
			)
			(layer "B.Fab")
		)
		(fp_line
			(start 0.12065 -0.2794)
			(end -0.12065 -0.2794)
			(stroke
				(width 0.1)
				(type default)
			)
			(layer "B.Fab")
		)
		(fp_line
			(start -0.12065 -0.2794)
			(end -0.12065 -0.3048)
			(stroke
				(width 0.1)
				(type default)
			)
			(layer "B.Fab")
		)
		(fp_line
			(start 0.12065 0.2794)
			(end 0.12065 0.3048)
			(stroke
				(width 0.1)
				(type default)
			)
			(layer "B.Fab")
		)
		(fp_line
			(start -0.120396 0.2794)
			(end 0.12065 0.2794)
			(stroke
				(width 0.1)
				(type default)
			)
			(layer "B.Fab")
		)
		(fp_line
			(start 0.67945 0.3048)
			(end 0.67945 -0.305054)
			(stroke
				(width 0.1)
				(type default)
			)
			(layer "B.Fab")
		)
		(fp_line
			(start 0.12065 0.3048)
			(end 0.67945 0.3048)
			(stroke
				(width 0.1)
				(type default)
			)
			(layer "B.Fab")
		)
		(fp_line
			(start -0.120396 0.3048)
			(end -0.120396 0.2794)
			(stroke
				(width 0.1)
				(type default)
			)
			(layer "B.Fab")
		)
		(fp_line
			(start -0.67945 0.3048)
			(end -0.120396 0.3048)
			(stroke
				(width 0.1)
				(type default)
			)
			(layer "B.Fab")
		)
		(pad "1" smd circle
			(at 0.40005 0 270)
			(size 0 0)
			(layers "B.Cu" "B.Mask" "B.Paste")
			(net "P0V9_CPU1_RT1_2A")
		)
		(pad "2" smd circle
			(at -0.40005 0 270)
			(size 0 0)
			(layers "B.Cu" "B.Mask" "B.Paste")
			(net "GND")
		)
	)
	(footprint ""
		(layer "B.Cu")
		(at 228.525578 -289.066732 90)
		(property "Reference" "R645"
			(at 0 0 90)
			(layer "B.SilkS")
			(hide yes)
			(effects
				(font
					(size 1.27 1.27)
				)
				(justify mirror)
			)
		)
		(property "Value" ""
			(at 0 0 90)
			(layer "B.Fab")
			(effects
				(font
					(size 1.27 1.27)
				)
				(justify mirror)
			)
		)
		(duplicate_pad_numbers_are_jumpers no)
		(fp_line
			(start 0.7874 -0.4064)
			(end -0.7874 -0.4064)
			(stroke
				(width 0.1524)
				(type default)
			)
			(layer "B.SilkS")
		)
		(fp_line
			(start -0.7874 -0.4064)
			(end -0.7874 0.4064)
			(stroke
				(width 0.1524)
				(type default)
			)
			(layer "B.SilkS")
		)
		(fp_line
			(start 0.7874 0.4064)
			(end 0.7874 -0.4064)
			(stroke
				(width 0.1524)
				(type default)
			)
			(layer "B.SilkS")
		)
		(fp_line
			(start -0.7874 0.4064)
			(end 0.7874 0.4064)
			(stroke
				(width 0.1524)
				(type default)
			)
			(layer "B.SilkS")
		)
		(fp_line
			(start 0.67945 -0.305054)
			(end 0.12065 -0.305054)
			(stroke
				(width 0.1)
				(type default)
			)
			(layer "B.Fab")
		)
		(fp_line
			(start 0.12065 -0.305054)
			(end 0.12065 -0.2794)
			(stroke
				(width 0.1)
				(type default)
			)
			(layer "B.Fab")
		)
		(fp_line
			(start -0.12065 -0.3048)
			(end -0.67945 -0.3048)
			(stroke
				(width 0.1)
				(type default)
			)
			(layer "B.Fab")
		)
		(fp_line
			(start -0.67945 -0.3048)
			(end -0.67945 0.3048)
			(stroke
				(width 0.1)
				(type default)
			)
			(layer "B.Fab")
		)
		(fp_line
			(start 0.12065 -0.2794)
			(end -0.12065 -0.2794)
			(stroke
				(width 0.1)
				(type default)
			)
			(layer "B.Fab")
		)
		(fp_line
			(start -0.12065 -0.2794)
			(end -0.12065 -0.3048)
			(stroke
				(width 0.1)
				(type default)
			)
			(layer "B.Fab")
		)
		(fp_line
			(start 0.12065 0.2794)
			(end 0.12065 0.3048)
			(stroke
				(width 0.1)
				(type default)
			)
			(layer "B.Fab")
		)
		(fp_line
			(start -0.120396 0.2794)
			(end 0.12065 0.2794)
			(stroke
				(width 0.1)
				(type default)
			)
			(layer "B.Fab")
		)
		(fp_line
			(start 0.67945 0.3048)
			(end 0.67945 -0.305054)
			(stroke
				(width 0.1)
				(type default)
			)
			(layer "B.Fab")
		)
		(fp_line
			(start 0.12065 0.3048)
			(end 0.67945 0.3048)
			(stroke
				(width 0.1)
				(type default)
			)
			(layer "B.Fab")
		)
		(fp_line
			(start -0.120396 0.3048)
			(end -0.120396 0.2794)
			(stroke
				(width 0.1)
				(type default)
			)
			(layer "B.Fab")
		)
		(fp_line
			(start -0.67945 0.3048)
			(end -0.120396 0.3048)
			(stroke
				(width 0.1)
				(type default)
			)
			(layer "B.Fab")
		)
		(pad "1" smd circle
			(at 0.40005 0 270)
			(size 0 0)
			(layers "B.Cu" "B.Mask" "B.Paste")
			(net "PWRGD_P1V8_RETIMER_CPU1")
		)
		(pad "2" smd circle
			(at -0.40005 0 270)
			(size 0 0)
			(layers "B.Cu" "B.Mask" "B.Paste")
			(net "FM_PWRGD_P1V8_RETIMER_CPU1")
		)
	)
	(footprint ""
		(layer "B.Cu")
		(at 123.357386 -266.005564)
		(property "Reference" "C3919"
			(at 0 0 0)
			(layer "B.SilkS")
			(hide yes)
			(effects
				(font
					(size 1.27 1.27)
				)
				(justify mirror)
			)
		)
		(property "Value" ""
			(at 0 0 0)
			(layer "B.Fab")
			(effects
				(font
					(size 1.27 1.27)
				)
				(justify mirror)
			)
		)
		(duplicate_pad_numbers_are_jumpers no)
		(fp_line
			(start -0.7874 -0.4064)
			(end -0.7874 0.4064)
			(stroke
				(width 0.1524)
				(type default)
			)
			(layer "B.SilkS")
		)
		(fp_line
			(start -0.7874 0.4064)
			(end 0.7874 0.4064)
			(stroke
				(width 0.1524)
				(type default)
			)
			(layer "B.SilkS")
		)
		(fp_line
			(start 0.7874 -0.4064)
			(end -0.7874 -0.4064)
			(stroke
				(width 0.1524)
				(type default)
			)
			(layer "B.SilkS")
		)
		(fp_line
			(start 0.7874 0.4064)
			(end 0.7874 -0.4064)
			(stroke
				(width 0.1524)
				(type default)
			)
			(layer "B.SilkS")
		)
		(fp_line
			(start -0.67945 -0.3048)
			(end -0.67945 0.3048)
			(stroke
				(width 0.1)
				(type default)
			)
			(layer "B.Fab")
		)
		(fp_line
			(start -0.67945 0.3048)
			(end -0.120396 0.3048)
			(stroke
				(width 0.1)
				(type default)
			)
			(layer "B.Fab")
		)
		(fp_line
			(start -0.12065 -0.3048)
			(end -0.67945 -0.3048)
			(stroke
				(width 0.1)
				(type default)
			)
			(layer "B.Fab")
		)
		(fp_line
			(start -0.12065 -0.2794)
			(end -0.12065 -0.3048)
			(stroke
				(width 0.1)
				(type default)
			)
			(layer "B.Fab")
		)
		(fp_line
			(start -0.120396 0.2794)
			(end 0.12065 0.2794)
			(stroke
				(width 0.1)
				(type default)
			)
			(layer "B.Fab")
		)
		(fp_line
			(start -0.120396 0.3048)
			(end -0.120396 0.2794)
			(stroke
				(width 0.1)
				(type default)
			)
			(layer "B.Fab")
		)
		(fp_line
			(start 0.12065 -0.305054)
			(end 0.12065 -0.2794)
			(stroke
				(width 0.1)
				(type default)
			)
			(layer "B.Fab")
		)
		(fp_line
			(start 0.12065 -0.2794)
			(end -0.12065 -0.2794)
			(stroke
				(width 0.1)
				(type default)
			)
			(layer "B.Fab")
		)
		(fp_line
			(start 0.12065 0.2794)
			(end 0.12065 0.3048)
			(stroke
				(width 0.1)
				(type default)
			)
			(layer "B.Fab")
		)
		(fp_line
			(start 0.12065 0.3048)
			(end 0.67945 0.3048)
			(stroke
				(width 0.1)
				(type default)
			)
			(layer "B.Fab")
		)
		(fp_line
			(start 0.67945 -0.305054)
			(end 0.12065 -0.305054)
			(stroke
				(width 0.1)
				(type default)
			)
			(layer "B.Fab")
		)
		(fp_line
			(start 0.67945 0.3048)
			(end 0.67945 -0.305054)
			(stroke
				(width 0.1)
				(type default)
			)
			(layer "B.Fab")
		)
		(pad "1" smd circle
			(at 0.40005 0 180)
			(size 0 0)
			(layers "B.Cu" "B.Mask" "B.Paste")
			(net "PVDD11_S3_P1")
		)
		(pad "2" smd circle
			(at -0.40005 0 180)
			(size 0 0)
			(layers "B.Cu" "B.Mask" "B.Paste")
			(net "GND")
		)
	)
)
